FILE_TYPE = CONNECTIVITY;
{Allegro Design Entry HDL 17.2-2016 S066 (3851973) 4/6/2020}
"PAGE_NUMBER" = 161;
0"NC";
1"SG\g";
2"XP3R3V_FPGA\g";
3"XP3R3V_FPGA\g";
4"SG\g";
5"SG\g";
6"SG\g";
7"FPGA_IN_MAC_10MHZ_OUT";
8"ANT2_IN";
9"FPGA_FLASH_CS_N";
10"PUDC";
11"ANT1_IN";
12"FPGA_D03";
13"UART_GPS_TX_FPGA_RX";
14"FPGA_FLASH_DQ0_MOSI";
15"FPGA_D01";
16"FPGA_D02";
17"FPGA_D00_MOSI";
18"ANT3_IN";
19"FPGA_FCS_B";
20"FPGA_IO_FT_USBDET_RST_N";
21"FPGA_OUT_SN_EEPROM_WP";
22"UART_GPS_RX_FPGA_TX";
23"ANT2_OUT";
24"FPGA_IN_GPSTP1_OUT";
25"FPGA_IN_GPSTP2_OUT";
26"FPGA_IN_MAC_ALARM_OUT_N";
27"FPGA_IN_MAC_BITE OUT";
28"FPGA_EEPROM_I2C_SDA";
29"FPGA_PCA9546_I2C_SDA";
30"FPGA_OUT_SEC_EEPROM_WP";
31"FPGA_EEPROM_I2C_SCL";
32"FPGA_OUT_PCA9546_RST_N";
33"ANT4_OUT";
34"ANT3_OUT";
35"ANT4_IN";
36"ANT1_OUT";
37"FPGA_OUT_GPS_RST_N";
38"UART_FT4232_TX_FPGA_RX";
39"UART_FT4232_RX_FPGA_TX";
40"UART_MAC_RX_FPGA_TX";
41"FPGA_PCA9546_I2C_SCL";
42"UART_MAC_TX_FPGA_RX";
43"MAC_USB_DM";
44"MAC_USB_DP";
45"FPGA_OUT_MACUSBPOWER_EN";
46"FPGA_M_RGB_LED_I2C_SCL";
47"FPGA_M_RGB_LED_I2C_SDA";
48"FPGA_OUT_RGB_LED_SHUTDOWN_N";
49"FPGA_FLASH_DQ1_MISO";
50"FPGA_FLASH_DQ3";
51"FPGA_FLASH_DQ2";
%"GND_SG"
"1","(-13150,6100)","0","cls","I136";
;
HDL_POWER"SG"
BODY_TYPE"PLUMBING"
CDS_LIB"cls"
CDS_LMAN_SYM_OUTLINE"0,0,100,-50";
"SGND"6;
%"RESISTOR"
"2","(-12600,7300)","1","passive","I140";
;
$LOCATION"R270"
CDS_LOCATION"R270"
$SEC"1"
CDS_SEC"1"
PACKAGE"0402"
VALUE"4.7KOHM"
TOLERANCE"1%"
CDS_LIB"passive"
CDS_LMAN_SYM_OUTLINE"-50,50,50,-100"
CLS_PN"G155-14701-01";
"1"
$PN"1"6;
"2"
$PN"2"24;
%"XC7A200T_2FBG484C_FBG484"
"2","(-9500,8650)","0","pld","I2";
;
$LOCATION"U24"
CDS_LOCATION"U24"
$SEC"2"
CDS_SEC"2"
CLS_PN"G240-10069-01"
CDS_LIB"pld"
CDS_LMAN_SYM_OUTLINE"0,0,2800,-5400";
"IO_L9P_T1_DQS_14"
$PN"Y21"0;
"IO_L9P_T1_DQS_13"
$PN"AA10"0;
"IO_L9N_T1_DQS_D13_14"
$PN"Y22"0;
"IO_L9N_T1_DQS_13"
$PN"AA11"0;
"IO_L15P_T2_DQS_RDWR_14* \B"
$PN"AA19"0;
"IO_L15P_T2_DQS_13"
$PN"T14"0;
"IO_L15N_T2_DQS_DOUT_CSO_14* \B"
$PN"AB20"0;
"IO_L15N_T2_DQS_13"
$PN"T15"0;
"IO_L14P_T2_SRCC_14"
$PN"V18"0;
"IO_L14P_T2_SRCC_13"
$PN"U15"0;
"IO_L14N_T2_SRCC_14"
$PN"V19"0;
"IO_L14N_T2_SRCC_13"
$PN"V15"45;
"IO_L13P_T2_MRCC_14"
$PN"Y18"48;
"IO_L13P_T2_MRCC_13"
$PN"V13"7;
"IO_L13N_T2_MRCC_14"
$PN"Y19"0;
"IO_L13N_T2_MRCC_13"
$PN"V14"0;
"IO_L12P_T1_MRCC_14"
$PN"W19"47;
"IO_L12P_T1_MRCC_13"
$PN"W11"34;
"IO_L12N_T1_MRCC_14"
$PN"W20"46;
"IO_L12N_T1_MRCC_13"
$PN"W12"33;
"IO_L11P_T1_SRCC_14"
$PN"U20"0;
"IO_L11P_T1_SRCC_13"
$PN"Y11"18;
"IO_L11N_T1_SRCC_14"
$PN"V20"0;
"IO_L11N_T1_SRCC_13"
$PN"Y12"35;
"IO_L10P_T1_D14_14"
$PN"AB21"0;
"IO_L10P_T1_13"
$PN"V10"36;
"IO_L10N_T1_D15_14"
$PN"AB22"0;
"IO_L10N_T1_13"
$PN"W10"23;
"IO_25_14"
$PN"N15"13;
"IO_0_14"
$PN"P20"22;
"IO_0_13"
$PN"Y17"0;
"IO_L16P_T2_CSI_14* \B"
$PN"V17"0;
"IO_L16P_T2_13"
$PN"W15"0;
"IO_L16N_T2_A15_D31_14"
$PN"W17"0;
"IO_L16N_T2_13"
$PN"W16"0;
"IO_L24P_T3_A01_D17_14"
$PN"P16"38;
"IO_L24N_T3_A00_D16_14"
$PN"R17"0;
"IO_L23P_T3_A03_D19_14"
$PN"N13"0;
"IO_L23N_T3_A02_D18_14"
$PN"N14"0;
"IO_L22P_T3_A05_D21_14"
$PN"P15"39;
"IO_L22N_T3_A04_D20_14"
$PN"R16"0;
"IO_L21P_T3_DQS_14"
$PN"N17"41;
"IO_L21N_T3_DQS_A06_D22_14"
$PN"P17"0;
"IO_L20P_T3_A08_D24_14"
$PN"R18"0;
"IO_L20N_T3_A07_D23_14"
$PN"T18"0;
"IO_L19P_T3_A10_D26_14"
$PN"P14"44;
"IO_L19N_T3_A09_D25_VREF_14"
$PN"R14"43;
"IO_L18P_T2_A12_D28_14"
$PN"U17"0;
"IO_L18N_T2_A11_D27_14"
$PN"U18"0;
"IO_L17P_T2_A14_D30_14"
$PN"AA18"40;
"IO_L17P_T2_13"
$PN"T16"29;
"IO_L17N_T2_A13_D29_14"
$PN"AB18"42;
"IO_L17N_T2_13"
$PN"U16"32;
"IO_L1P_T0_D00_MOSI_14"
$PN"P22"17;
"IO_L1P_T0_13"
$PN"Y16"37;
"IO_L1N_T0_D01_DIN_14"
$PN"R22"15;
"IO_L1N_T0_13"
$PN"AA16"0;
"IO_L8P_T1_D11_14"
$PN"AA20"8;
"IO_L8P_T1_13"
$PN"AA9"27;
"IO_L8N_T1_D12_14"
$PN"AA21"11;
"IO_L8N_T1_13"
$PN"AB10"26;
"IO_L7P_T1_D09_14"
$PN"W21"0;
"IO_L7P_T1_13"
$PN"AB11"0;
"IO_L7N_T1_D10_14"
$PN"W22"0;
"IO_L7N_T1_13"
$PN"AB12"0;
"IO_L6P_T0_FCS_B_14"
$PN"T19"19;
"IO_L6P_T0_13"
$PN"W14"24;
"IO_L6N_T0_VREF_13"
$PN"Y14"25;
"IO_L6N_T0_D08_VREF_14"
$PN"T20"0;
"IO_L5P_T0_D06_14"
$PN"P19"0;
"IO_L5P_T0_13"
$PN"Y13"0;
"IO_L5N_T0_D07_14"
$PN"R19"0;
"IO_L5N_T0_13"
$PN"AA14"0;
"IO_L4P_T0_D04_14"
$PN"T21"0;
"IO_L4P_T0_13"
$PN"AA15"20;
"IO_L4N_T0_D05_14"
$PN"U21"0;
"IO_L4N_T0_13"
$PN"AB15"0;
"IO_L3P_T0_DQS_PUDC_14* \B"
$PN"U22"10;
"IO_L3P_T0_DQS_13"
$PN"AA13"21;
"IO_L3N_T0_DQS_EMCCLK_14"
$PN"V22"0;
"IO_L3N_T0_DQS_13"
$PN"AB13"30;
"IO_L2P_T0_D02_14"
$PN"P21"16;
"IO_L2P_T0_13"
$PN"AB16"31;
"IO_L2N_T0_D03_14"
$PN"R21"12;
"IO_L2N_T0_13"
$PN"AB17"28;
%"RESISTOR"
"2","(-12600,7200)","1","passive","I200";
;
LOCATION"R271"
$SEC"1"
CDS_SEC"1"
VALUE"4.7KOHM"
PACKAGE"0402"
NO_ASSY"TRUE"
TOLERANCE"1%"
CLS_PN"G155-14701-01"
CDS_LMAN_SYM_OUTLINE"-50,50,50,-100"
CDS_LIB"passive";
"1"
$PN"1"6;
"2"
$PN"2"25;
%"RESISTOR"
"2","(-12600,6900)","1","passive","I201";
;
LOCATION"R288"
$SEC"1"
CDS_SEC"1"
VALUE"4.7KOHM"
PACKAGE"0402"
CLS_PN"G155-14701-01"
TOLERANCE"1%"
CDS_LMAN_SYM_OUTLINE"-50,50,50,-100"
CDS_LIB"passive";
"1"
$PN"1"6;
"2"
$PN"2"27;
%"GND_SG"
"1","(-3000,4250)","0","cls","I238";
;
HDL_POWER"SG"
CDS_LIB"cls"
CDS_LMAN_SYM_OUTLINE"0,0,100,-50"
BODY_TYPE"PLUMBING";
"SGND"5;
%"RESISTOR"
"1","(-3650,4400)","4","passive","I239";
;
$LOCATION"R437"
CDS_LOCATION"R437"
$SEC"1"
CDS_SEC"1"
NO_ASSY"TRUE"
VALUE"15KOHM"
PACKAGE"0402"
CDS_LIB"passive"
CDS_LMAN_SYM_OUTLINE"-50,50,100,-50"
TOLERANCE"1%"
CLS_PN"G155-11502-01";
"1"
$PN"1"5;
"2"
$PN"2"43;
%"RESISTOR"
"1","(-3650,4500)","4","passive","I240";
;
$LOCATION"R436"
CDS_LOCATION"R436"
$SEC"1"
CDS_SEC"1"
NO_ASSY"TRUE"
VALUE"15KOHM"
PACKAGE"0402"
CDS_LIB"passive"
CDS_LMAN_SYM_OUTLINE"-50,50,100,-50"
TOLERANCE"1%"
CLS_PN"G155-11502-01";
"1"
$PN"1"5;
"2"
$PN"2"44;
%"RESISTOR"
"2","(-12550,6200)","1","passive","I241";
;
$LOCATION"R501"
CDS_LOCATION"R501"
$SEC"1"
CDS_SEC"1"
NO_ASSY"TRUE"
PACKAGE"0402"
VALUE"4.7KOHM"
CDS_LIB"passive"
CDS_LMAN_SYM_OUTLINE"-50,50,50,-100"
CLS_PN"G155-14701-01"
TOLERANCE"1%";
"1"
$PN"1"6;
"2"
$PN"2"35;
%"RESISTOR"
"2","(-12550,6300)","1","passive","I242";
;
$LOCATION"R500"
CDS_LOCATION"R500"
$SEC"1"
CDS_SEC"1"
VALUE"4.7KOHM"
PACKAGE"0402"
NO_ASSY"TRUE"
TOLERANCE"1%"
CLS_PN"G155-14701-01"
CDS_LMAN_SYM_OUTLINE"-50,50,50,-100"
CDS_LIB"passive";
"1"
$PN"1"6;
"2"
$PN"2"18;
%"RESISTOR"
"2","(-3850,6600)","1","passive","I244";
;
$LOCATION"R504"
CDS_LOCATION"R504"
$SEC"1"
CDS_SEC"1"
NO_ASSY"TRUE"
VALUE"4.7KOHM"
PACKAGE"0402"
CDS_LIB"passive"
CDS_LMAN_SYM_OUTLINE"-50,50,50,-100"
CLS_PN"G155-14701-01"
TOLERANCE"1%";
"1"
$PN"1"11;
"2"
$PN"2"4;
%"GND_SG"
"1","(-3200,6450)","0","cls","I245";
;
HDL_POWER"SG"
BODY_TYPE"PLUMBING"
CDS_LIB"cls"
CDS_LMAN_SYM_OUTLINE"0,0,100,-50";
"SGND"4;
%"RESISTOR"
"2","(-3850,6700)","1","passive","I246";
;
$LOCATION"R503"
CDS_LOCATION"R503"
$SEC"1"
CDS_SEC"1"
NO_ASSY"TRUE"
VALUE"4.7KOHM"
PACKAGE"0402"
CDS_LIB"passive"
CDS_LMAN_SYM_OUTLINE"-50,50,50,-100"
CLS_PN"G155-14701-01"
TOLERANCE"1%";
"1"
$PN"1"8;
"2"
$PN"2"4;
%"RESISTOR"
"2","(-12550,5900)","1","passive","I247";
;
$LOCATION"R502"
CDS_LOCATION"R502"
$SEC"1"
CDS_SEC"1"
VALUE"4.7KOHM"
PACKAGE"0402"
CLS_PN"G155-14701-01"
TOLERANCE"1%"
CDS_LMAN_SYM_OUTLINE"-50,50,50,-100"
CDS_LIB"passive";
"1"
$PN"1"2;
"2"
$PN"2"7;
%"VCC"
"1","(-13250,5850)","1","cls","I248";
;
VOLTAGE"3.3V"
HDL_POWER"XP3R3V_FPGA"
BODY_TYPE"PLUMBING"
CDS_LMAN_SYM_OUTLINE"-250,250,250,-250"
CDS_LIB"cls";
"$PIN0"2;
%"VCC"
"1","(-2150,8150)","0","cls","I249";
;
HDL_POWER"XP3R3V_FPGA"
VOLTAGE"3.3V"
CDS_LIB"cls"
CDS_LMAN_SYM_OUTLINE"-250,250,250,-250"
BODY_TYPE"PLUMBING";
"$PIN0"3;
%"GND_SG"
"1","(-2200,7550)","0","cls","I250";
;
HDL_POWER"SG"
CDS_LIB"cls"
CDS_LMAN_SYM_OUTLINE"0,0,100,-50"
BODY_TYPE"PLUMBING";
"SGND"1;
%"RESISTOR"
"2","(-2800,8000)","1","passive","I251";
;
$LOCATION"R435"
CDS_LOCATION"R435"
$SEC"1"
CDS_SEC"1"
PACKAGE"0402"
VALUE"100KOHM"
CLS_PN"G155-11003-01"
CDS_LMAN_SYM_OUTLINE"-50,50,50,-100"
CDS_LIB"passive"
TOLERANCE"1%";
"1"
$PN"1"49;
"2"
$PN"2"3;
%"RESISTOR"
"1","(-2800,7750)","0","passive","I252";
;
$LOCATION"R223"
CDS_LOCATION"R223"
$SEC"1"
CDS_SEC"1"
PACKAGE"0402"
VALUE"1KOHM"
TOLERANCE"1%"
CDS_LIB"passive"
CDS_LMAN_SYM_OUTLINE"-50,50,100,-50"
CLS_PN"G155-11001-01";
"1"
$PN"1"10;
"2"
$PN"2"3;
%"RESISTOR"
"1","(-2750,7650)","4","passive","I253";
;
$LOCATION"R224"
CDS_LOCATION"R224"
$SEC"1"
CDS_SEC"1"
NO_ASSY"TRUE"
PACKAGE"0402"
VALUE"1KOHM"
CDS_LIB"passive"
CDS_LMAN_SYM_OUTLINE"-50,50,100,-50"
TOLERANCE"1%"
CLS_PN"G155-11001-01";
"1"
$PN"1"1;
"2"
$PN"2"10;
%"RESISTOR"
"1","(-5350,8150)","0","passive","I258";
;
$LOCATION"R234"
CDS_LOCATION"R234"
$SEC"1"
CDS_SEC"1"
VALUE"33OHM"
PACKAGE"0402"
TOLERANCE"1%"
CLS_PN"G155-133R0-01"
CDS_LMAN_SYM_OUTLINE"-50,50,100,-50"
CDS_LIB"passive";
"1"
$PN"1"17;
"2"
$PN"2"14;
%"RESISTOR"
"1","(-5350,8050)","0","passive","I259";
;
$LOCATION"R238"
CDS_LOCATION"R238"
$SEC"1"
CDS_SEC"1"
PACKAGE"0402"
VALUE"33OHM"
TOLERANCE"1%"
CLS_PN"G155-133R0-01"
CDS_LMAN_SYM_OUTLINE"-50,50,100,-50"
CDS_LIB"passive";
"1"
$PN"1"15;
"2"
$PN"2"49;
%"RESISTOR"
"1","(-5350,7850)","0","passive","I260";
;
$LOCATION"R348"
CDS_LOCATION"R348"
$SEC"1"
CDS_SEC"1"
VALUE"33OHM"
PACKAGE"0402"
TOLERANCE"1%"
CLS_PN"G155-133R0-01"
CDS_LMAN_SYM_OUTLINE"-50,50,100,-50"
CDS_LIB"passive";
"1"
$PN"1"12;
"2"
$PN"2"50;
%"RESISTOR"
"1","(-5350,7950)","0","passive","I261";
;
$LOCATION"R339"
CDS_LOCATION"R339"
$SEC"1"
CDS_SEC"1"
PACKAGE"0402"
VALUE"33OHM"
TOLERANCE"1%"
CLS_PN"G155-133R0-01"
CDS_LMAN_SYM_OUTLINE"-50,50,100,-50"
CDS_LIB"passive";
"1"
$PN"1"16;
"2"
$PN"2"51;
%"RESISTOR"
"1","(-5350,7150)","0","passive","I263";
;
$LOCATION"R362"
CDS_LOCATION"R362"
$SEC"1"
CDS_SEC"1"
PACKAGE"0402"
VALUE"33OHM"
CDS_LIB"passive"
CDS_LMAN_SYM_OUTLINE"-50,50,100,-50"
CLS_PN"G155-133R0-01"
TOLERANCE"1%";
"1"
$PN"1"19;
"2"
$PN"2"9;
END.
